# BASEBOARD_FAB2 (Tioga Pass) — schematic netlist excerpt (pin names and nets, part order shuffled) for the footprints in the layout excerpt that follows; sources: Cadence DE-HDL packaged netlist, KiCad conversion of Wiwynn_Tioga_Pass_MB.brd

R8F27  RES  33.2 1% CHIP  pkg 0402  page 101 : A = CLK_32K_SUSCLK_PLD_R ; B = CLK_32K_SUSCLK_PLD
C7G2  CAPP  270UF 16V 20% OSCON  pkg 2626  page 217 : A = VR_FET_SW_P12V_STBY_PVDDQ_ABC ; B = GND

(kicad_pcb
	(version 20260206)
	(generator "pcbnew")
	(generator_version "10.0")
	(general
		(thickness 1.6)
		(legacy_teardrops no)
	)
	(paper "A4")
	(title_block
		(title "Wiwynn_Tioga_Pass_MB.brd")
		(comment 1 "Tioga Pass / footprints 570-571 of 4770")
	)
	(layers
		(0 "F.Cu" signal "TOP")
		(4 "In1.Cu" signal "L2GND")
		(6 "In2.Cu" signal "L3")
		(8 "In3.Cu" signal "L4GND")
		(10 "In4.Cu" signal "L5")
		(12 "In5.Cu" signal "L6GND")
		(14 "In6.Cu" signal "L7VCC")
		(16 "In7.Cu" signal "L8VCC")
		(18 "In8.Cu" signal "L9GND")
		(20 "In9.Cu" signal "L10")
		(22 "In10.Cu" signal "L11GND")
		(24 "In11.Cu" signal "L12")
		(26 "In12.Cu" signal "L13GND")
		(2 "B.Cu" signal "BOTTOM")
		(9 "F.Adhes" user "F.Adhesive")
		(11 "B.Adhes" user "B.Adhesive")
		(13 "F.Paste" user "Package Geometry/Pastemask Top")
		(15 "B.Paste" user "Package Geometry/Pastemask Bottom")
		(5 "F.SilkS" user "Ref Des/Silkscreen Top")
		(7 "B.SilkS" user "Ref Des/Silkscreen Bottom")
		(1 "F.Mask" user "Board Geometry/Soldermask Top")
		(3 "B.Mask" user "Board Geometry/Soldermask Bottom")
		(17 "Dwgs.User" user "User.Drawings")
		(19 "Cmts.User" user "User.Comments")
		(21 "Eco1.User" user "User.Eco1")
		(23 "Eco2.User" user "User.Eco2")
		(25 "Edge.Cuts" user "Board Geometry/Outline")
		(27 "Margin" user)
		(31 "F.CrtYd" user "Package Geometry/Place Bound Top")
		(29 "B.CrtYd" user "Package Geometry/Place Bound Bottom")
		(35 "F.Fab" user "Ref Des/Assembly Top")
		(33 "B.Fab" user "Ref Des/Assembly Bottom")
	)
	(footprint ""
		(layer "F.Cu")
		(at 353.5807 -15.737586 90)
		(property "Reference" "C7G2"
			(at -4.21767 2.921 0)
			(unlocked yes)
			(layer "F.SilkS")
			(effects
				(font
					(size 0.7874 0.5842)
					(thickness 0.1524)
				)
				(justify left)
			)
		)
		(property "Value" ""
			(at 0 0 90)
			(layer "F.Fab")
			(effects
				(font
					(size 1.27 1.27)
				)
			)
		)
		(duplicate_pad_numbers_are_jumpers no)
		(fp_line
			(start 0.9017 -1.714246)
			(end 0.7239 -1.714246)
			(stroke
				(width 0.1524)
				(type default)
			)
			(layer "F.SilkS")
		)
		(fp_line
			(start -0.7239 -1.714246)
			(end -0.9017 -1.714246)
			(stroke
				(width 0.1524)
				(type default)
			)
			(layer "F.SilkS")
		)
		(fp_line
			(start -0.9017 -1.714246)
			(end -0.9017 1.587754)
			(stroke
				(width 0.1524)
				(type default)
			)
			(layer "F.SilkS")
		)
		(fp_line
			(start 2.638044 -0.733044)
			(end 0.9017 -0.733044)
			(stroke
				(width 0.1524)
				(type default)
			)
			(layer "F.SilkS")
		)
		(fp_line
			(start -0.9017 -0.733044)
			(end -2.638044 -0.733044)
			(stroke
				(width 0.1524)
				(type default)
			)
			(layer "F.SilkS")
		)
		(fp_line
			(start -2.638044 -0.733044)
			(end -3.400044 0.028956)
			(stroke
				(width 0.1524)
				(type default)
			)
			(layer "F.SilkS")
		)
		(fp_line
			(start 3.400044 0.028956)
			(end 2.638044 -0.733044)
			(stroke
				(width 0.1524)
				(type default)
			)
			(layer "F.SilkS")
		)
		(fp_line
			(start -3.400044 0.028956)
			(end -3.400044 6.067044)
			(stroke
				(width 0.1524)
				(type default)
			)
			(layer "F.SilkS")
		)
		(fp_line
			(start 0.9017 1.587754)
			(end 0.9017 -1.714246)
			(stroke
				(width 0.1524)
				(type default)
			)
			(layer "F.SilkS")
		)
		(fp_line
			(start 0.7239 1.587754)
			(end 0.9017 1.587754)
			(stroke
				(width 0.1524)
				(type default)
			)
			(layer "F.SilkS")
		)
		(fp_line
			(start -0.9017 1.587754)
			(end -0.7239 1.587754)
			(stroke
				(width 0.1524)
				(type default)
			)
			(layer "F.SilkS")
		)
		(fp_line
			(start 3.400044 6.067044)
			(end 3.400044 0.028956)
			(stroke
				(width 0.1524)
				(type default)
			)
			(layer "F.SilkS")
		)
		(fp_line
			(start 0.9017 6.067044)
			(end 3.400044 6.067044)
			(stroke
				(width 0.1524)
				(type default)
			)
			(layer "F.SilkS")
		)
		(fp_line
			(start -3.400044 6.067044)
			(end -0.9017 6.067044)
			(stroke
				(width 0.1524)
				(type default)
			)
			(layer "F.SilkS")
		)
		(fp_poly
			(pts
				(xy -3.400044 6.067044) (xy 3.400044 6.067044) (xy 3.400044 0.028956) (xy 2.638044 -0.733044) (xy -2.638044 -0.733044)
				(xy -3.400044 0.028956)
			)
			(stroke
				(width 0)
				(type default)
			)
			(fill no)
			(layer "F.CrtYd")
		)
		(fp_line
			(start 2.638044 -0.733044)
			(end -2.638044 -0.733044)
			(stroke
				(width 0.1)
				(type default)
			)
			(layer "F.Fab")
		)
		(fp_line
			(start -2.638044 -0.733044)
			(end -3.400044 0.028956)
			(stroke
				(width 0.1)
				(type default)
			)
			(layer "F.Fab")
		)
		(fp_line
			(start 3.400044 0.028956)
			(end 2.638044 -0.733044)
			(stroke
				(width 0.1)
				(type default)
			)
			(layer "F.Fab")
		)
		(fp_line
			(start -3.400044 0.028956)
			(end -3.400044 6.067044)
			(stroke
				(width 0.1)
				(type default)
			)
			(layer "F.Fab")
		)
		(fp_line
			(start 3.400044 6.067044)
			(end 3.400044 0.028956)
			(stroke
				(width 0.1)
				(type default)
			)
			(layer "F.Fab")
		)
		(fp_line
			(start -3.400044 6.067044)
			(end 3.400044 6.067044)
			(stroke
				(width 0.1)
				(type default)
			)
			(layer "F.Fab")
		)
		(fp_circle
			(center 0 2.667)
			(end 0 6.067044)
			(stroke
				(width 0.1)
				(type default)
			)
			(fill no)
			(layer "F.Fab")
		)
		(pad "1" smd rect
			(at 0 0 90)
			(size 0.7874 3.429)
			(layers "F.Cu" "F.Mask" "F.Paste")
			(net "VR_FET_SW_P12V_STBY_PVDDQ_ABC")
		)
		(pad "2" smd rect
			(at 0 5.334 90)
			(size 0.7874 3.429)
			(layers "F.Cu" "F.Mask" "F.Paste")
			(net "GND")
		)
	)
	(footprint ""
		(layer "F.Cu")
		(at 482.67366 -29.28112 90)
		(property "Reference" "R8F27"
			(at 0 0 90)
			(layer "F.SilkS")
			(hide yes)
			(effects
				(font
					(size 1.27 1.27)
				)
			)
		)
		(property "Value" ""
			(at 0 0 90)
			(layer "F.Fab")
			(effects
				(font
					(size 1.27 1.27)
				)
			)
		)
		(duplicate_pad_numbers_are_jumpers no)
		(fp_poly
			(pts
				(xy -0.2794 -0.1016) (xy 0.2794 -0.1016) (xy 0.2794 0.9906) (xy -0.2794 0.9906)
			)
			(stroke
				(width 0)
				(type default)
			)
			(fill no)
			(layer "F.CrtYd")
		)
		(fp_line
			(start 0.2794 -0.1016)
			(end -0.2794 -0.1016)
			(stroke
				(width 0.1)
				(type default)
			)
			(layer "F.Fab")
		)
		(fp_line
			(start -0.2794 -0.1016)
			(end -0.2794 0.9906)
			(stroke
				(width 0.1)
				(type default)
			)
			(layer "F.Fab")
		)
		(fp_line
			(start 0.2794 0.9906)
			(end 0.2794 -0.1016)
			(stroke
				(width 0.1)
				(type default)
			)
			(layer "F.Fab")
		)
		(fp_line
			(start -0.2794 0.9906)
			(end 0.2794 0.9906)
			(stroke
				(width 0.1)
				(type default)
			)
			(layer "F.Fab")
		)
		(pad "1" smd rect
			(at 0 0 90)
			(size 0.508 0.508)
			(layers "F.Cu" "F.Mask" "F.Paste")
			(net "CLK_32K_SUSCLK_PLD_R")
		)
		(pad "2" smd rect
			(at 0 0.889 90)
			(size 0.508 0.508)
			(layers "F.Cu" "F.Mask" "F.Paste")
			(net "CLK_32K_SUSCLK_PLD")
		)
		(zone
			(layer "F.Cu")
			(hatch none 0.5)
			(connect_pads
				(clearance 0)
			)
			(min_thickness 0.25)
			(keepout
				(tracks allowed)
				(vias not_allowed)
				(pads allowed)
				(copperpour not_allowed)
				(footprints allowed)
			)
			(placement
				(enabled no)
				(sheetname "")
			)
			(fill
				(thermal_gap 0.5)
				(thermal_bridge_width 0.5)
				(island_removal_mode 0)
			)
			(polygon
				(pts
					(xy 482.92766 -29.02712) (xy 482.92766 -29.53512) (xy 483.30866 -29.53512) (xy 483.30866 -29.02712)
				)
			)
		)
		(zone
			(layer "F.Cu")
			(hatch none 0.5)
			(connect_pads
				(clearance 0)
			)
			(min_thickness 0.25)
			(keepout
				(tracks not_allowed)
				(vias allowed)
				(pads allowed)
				(copperpour not_allowed)
				(footprints allowed)
			)
			(placement
				(enabled no)
				(sheetname "")
			)
			(fill
				(thermal_gap 0.5)
				(thermal_bridge_width 0.5)
				(island_removal_mode 0)
			)
			(polygon
				(pts
					(xy 483.30866 -29.02712) (xy 483.30866 -29.53512) (xy 482.92766 -29.53512) (xy 482.92766 -29.02712)
				)
			)
		)
	)
)
